# T6G (Grand Teton) — schematic netlist excerpt (pin names and nets, part order shuffled) for the footprints in the layout excerpt that follows; sources: Cadence DE-HDL packaged netlist, KiCad conversion of 04192023_DAF0TMB3IC0_F0TG_MB_C_brd_V02_OCP.brd

PR251  Q_RES  0 5% CHIP  pkg 0402LF  page 217 : A = P12V_AUX ; B = PVDDCR_CPU1_P1_VINSEN
R3756  Q_RES  0 5% CHIP  pkg 0402LF  page 236 : A = SMB_INA230_2_3V3AUX_SDA_R ; B = SMB_INA230_2_3V3AUX_SDA_R1

(kicad_pcb
	(version 20260206)
	(generator "pcbnew")
	(generator_version "10.0")
	(general
		(thickness 1.6)
		(legacy_teardrops no)
	)
	(paper "A4")
	(title_block
		(title "04192023_DAF0TMB3IC0_F0TG_MB_C_brd_V02_OCP.brd")
		(comment 1 "Grand Teton / footprints 2459-2460 of 8354")
	)
	(layers
		(0 "F.Cu" signal "TOP")
		(4 "In1.Cu" signal "GND")
		(6 "In2.Cu" signal "IN1")
		(8 "In3.Cu" signal "GND1")
		(10 "In4.Cu" signal "IN2")
		(12 "In5.Cu" signal "GND2")
		(14 "In6.Cu" signal "IN3")
		(16 "In7.Cu" signal "GND3")
		(18 "In8.Cu" signal "VCC")
		(20 "In9.Cu" signal "VCC1")
		(22 "In10.Cu" signal "GND4")
		(24 "In11.Cu" signal "IN4")
		(26 "In12.Cu" signal "GND5")
		(28 "In13.Cu" signal "IN5")
		(30 "In14.Cu" signal "GND6")
		(32 "In15.Cu" signal "IN6")
		(34 "In16.Cu" signal "GND7")
		(2 "B.Cu" signal "BOTTOM")
		(9 "F.Adhes" user "F.Adhesive")
		(11 "B.Adhes" user "B.Adhesive")
		(13 "F.Paste" user "Package Geometry/Pastemask Top")
		(15 "B.Paste" user "Package Geometry/Pastemask Bottom")
		(5 "F.SilkS" user "Ref Des/Silkscreen Top")
		(7 "B.SilkS" user "Ref Des/Silkscreen Bottom")
		(1 "F.Mask" user "Board Geometry/Soldermask Top")
		(3 "B.Mask" user "Board Geometry/Soldermask Bottom")
		(17 "Dwgs.User" user "User.Drawings")
		(19 "Cmts.User" user "User.Comments")
		(21 "Eco1.User" user "User.Eco1")
		(23 "Eco2.User" user "User.Eco2")
		(25 "Edge.Cuts" user "Board Geometry/Outline")
		(27 "Margin" user)
		(31 "F.CrtYd" user "Package Geometry/Place Bound Top")
		(29 "B.CrtYd" user "Package Geometry/Place Bound Bottom")
		(35 "F.Fab" user "Ref Des/Assembly Top")
		(33 "B.Fab" user "Ref Des/Assembly Bottom")
	)
	(footprint ""
		(layer "F.Cu")
		(at 38.354 -366.776 90)
		(property "Reference" "PR251"
			(at 0 0 90)
			(layer "F.SilkS")
			(hide yes)
			(effects
				(font
					(size 1.27 1.27)
				)
			)
		)
		(property "Value" ""
			(at 0 0 90)
			(layer "F.Fab")
			(effects
				(font
					(size 1.27 1.27)
				)
			)
		)
		(duplicate_pad_numbers_are_jumpers no)
		(fp_line
			(start 0.7874 -0.4064)
			(end 0.7874 0.4064)
			(stroke
				(width 0.1524)
				(type default)
			)
			(layer "F.SilkS")
		)
		(fp_line
			(start -0.7874 -0.4064)
			(end 0.7874 -0.4064)
			(stroke
				(width 0.1524)
				(type default)
			)
			(layer "F.SilkS")
		)
		(fp_line
			(start 0.7874 0.4064)
			(end -0.7874 0.4064)
			(stroke
				(width 0.1524)
				(type default)
			)
			(layer "F.SilkS")
		)
		(fp_line
			(start -0.7874 0.4064)
			(end -0.7874 -0.4064)
			(stroke
				(width 0.1524)
				(type default)
			)
			(layer "F.SilkS")
		)
		(fp_line
			(start -0.12065 -0.305054)
			(end -0.12065 -0.2794)
			(stroke
				(width 0.1)
				(type default)
			)
			(layer "F.Fab")
		)
		(fp_line
			(start -0.67945 -0.305054)
			(end -0.12065 -0.305054)
			(stroke
				(width 0.1)
				(type default)
			)
			(layer "F.Fab")
		)
		(fp_line
			(start 0.67945 -0.3048)
			(end 0.67945 0.3048)
			(stroke
				(width 0.1)
				(type default)
			)
			(layer "F.Fab")
		)
		(fp_line
			(start 0.12065 -0.3048)
			(end 0.67945 -0.3048)
			(stroke
				(width 0.1)
				(type default)
			)
			(layer "F.Fab")
		)
		(fp_line
			(start 0.12065 -0.2794)
			(end 0.12065 -0.3048)
			(stroke
				(width 0.1)
				(type default)
			)
			(layer "F.Fab")
		)
		(fp_line
			(start -0.12065 -0.2794)
			(end 0.12065 -0.2794)
			(stroke
				(width 0.1)
				(type default)
			)
			(layer "F.Fab")
		)
		(fp_line
			(start 0.120396 0.2794)
			(end -0.12065 0.2794)
			(stroke
				(width 0.1)
				(type default)
			)
			(layer "F.Fab")
		)
		(fp_line
			(start -0.12065 0.2794)
			(end -0.12065 0.3048)
			(stroke
				(width 0.1)
				(type default)
			)
			(layer "F.Fab")
		)
		(fp_line
			(start 0.67945 0.3048)
			(end 0.120396 0.3048)
			(stroke
				(width 0.1)
				(type default)
			)
			(layer "F.Fab")
		)
		(fp_line
			(start 0.120396 0.3048)
			(end 0.120396 0.2794)
			(stroke
				(width 0.1)
				(type default)
			)
			(layer "F.Fab")
		)
		(fp_line
			(start -0.12065 0.3048)
			(end -0.67945 0.3048)
			(stroke
				(width 0.1)
				(type default)
			)
			(layer "F.Fab")
		)
		(fp_line
			(start -0.67945 0.3048)
			(end -0.67945 -0.305054)
			(stroke
				(width 0.1)
				(type default)
			)
			(layer "F.Fab")
		)
		(pad "1" smd circle
			(at -0.40005 0 90)
			(size 0 0)
			(layers "F.Cu" "F.Mask" "F.Paste")
			(net "P12V_AUX")
		)
		(pad "2" smd circle
			(at 0.40005 0 90)
			(size 0 0)
			(layers "F.Cu" "F.Mask" "F.Paste")
			(net "PVDDCR_CPU1_P1_VINSEN")
		)
	)
	(footprint ""
		(layer "F.Cu")
		(at 213.41588 -50.637948 90)
		(property "Reference" "R3756"
			(at 0 0 90)
			(layer "F.SilkS")
			(hide yes)
			(effects
				(font
					(size 1.27 1.27)
				)
			)
		)
		(property "Value" ""
			(at 0 0 90)
			(layer "F.Fab")
			(effects
				(font
					(size 1.27 1.27)
				)
			)
		)
		(duplicate_pad_numbers_are_jumpers no)
		(fp_line
			(start 0.7874 -0.4064)
			(end 0.7874 0.4064)
			(stroke
				(width 0.1524)
				(type default)
			)
			(layer "F.SilkS")
		)
		(fp_line
			(start -0.7874 -0.4064)
			(end 0.7874 -0.4064)
			(stroke
				(width 0.1524)
				(type default)
			)
			(layer "F.SilkS")
		)
		(fp_line
			(start 0.7874 0.4064)
			(end -0.7874 0.4064)
			(stroke
				(width 0.1524)
				(type default)
			)
			(layer "F.SilkS")
		)
		(fp_line
			(start -0.7874 0.4064)
			(end -0.7874 -0.4064)
			(stroke
				(width 0.1524)
				(type default)
			)
			(layer "F.SilkS")
		)
		(fp_line
			(start -0.12065 -0.305054)
			(end -0.12065 -0.2794)
			(stroke
				(width 0.1)
				(type default)
			)
			(layer "F.Fab")
		)
		(fp_line
			(start -0.67945 -0.305054)
			(end -0.12065 -0.305054)
			(stroke
				(width 0.1)
				(type default)
			)
			(layer "F.Fab")
		)
		(fp_line
			(start 0.67945 -0.3048)
			(end 0.67945 0.3048)
			(stroke
				(width 0.1)
				(type default)
			)
			(layer "F.Fab")
		)
		(fp_line
			(start 0.12065 -0.3048)
			(end 0.67945 -0.3048)
			(stroke
				(width 0.1)
				(type default)
			)
			(layer "F.Fab")
		)
		(fp_line
			(start 0.12065 -0.2794)
			(end 0.12065 -0.3048)
			(stroke
				(width 0.1)
				(type default)
			)
			(layer "F.Fab")
		)
		(fp_line
			(start -0.12065 -0.2794)
			(end 0.12065 -0.2794)
			(stroke
				(width 0.1)
				(type default)
			)
			(layer "F.Fab")
		)
		(fp_line
			(start 0.120396 0.2794)
			(end -0.12065 0.2794)
			(stroke
				(width 0.1)
				(type default)
			)
			(layer "F.Fab")
		)
		(fp_line
			(start -0.12065 0.2794)
			(end -0.12065 0.3048)
			(stroke
				(width 0.1)
				(type default)
			)
			(layer "F.Fab")
		)
		(fp_line
			(start 0.67945 0.3048)
			(end 0.120396 0.3048)
			(stroke
				(width 0.1)
				(type default)
			)
			(layer "F.Fab")
		)
		(fp_line
			(start 0.120396 0.3048)
			(end 0.120396 0.2794)
			(stroke
				(width 0.1)
				(type default)
			)
			(layer "F.Fab")
		)
		(fp_line
			(start -0.12065 0.3048)
			(end -0.67945 0.3048)
			(stroke
				(width 0.1)
				(type default)
			)
			(layer "F.Fab")
		)
		(fp_line
			(start -0.67945 0.3048)
			(end -0.67945 -0.305054)
			(stroke
				(width 0.1)
				(type default)
			)
			(layer "F.Fab")
		)
		(pad "1" smd circle
			(at -0.40005 0 90)
			(size 0 0)
			(layers "F.Cu" "F.Mask" "F.Paste")
			(net "SMB_INA230_2_3V3AUX_SDA_R")
		)
		(pad "2" smd circle
			(at 0.40005 0 90)
			(size 0 0)
			(layers "F.Cu" "F.Mask" "F.Paste")
			(net "SMB_INA230_2_3V3AUX_SDA_R1")
		)
	)
)
